(kicad_pcb
	(version 20260206)
	(generator "pcbnew")
	(generator_version "10.0")
	(general
		(thickness 1.6)
		(legacy_teardrops no)
	)
	(paper "A4")
	(title_block
		(title "Wiwynn_Tioga_Pass_MB.brd")
		(comment 1 "Tioga Pass / footprint 1033 of 4770 (EU9E1), pads 1-42 of 65")
	)
	(layers
		(0 "F.Cu" signal "TOP")
		(4 "In1.Cu" signal "L2GND")
		(6 "In2.Cu" signal "L3")
		(8 "In3.Cu" signal "L4GND")
		(10 "In4.Cu" signal "L5")
		(12 "In5.Cu" signal "L6GND")
		(14 "In6.Cu" signal "L7VCC")
		(16 "In7.Cu" signal "L8VCC")
		(18 "In8.Cu" signal "L9GND")
		(20 "In9.Cu" signal "L10")
		(22 "In10.Cu" signal "L11GND")
		(24 "In11.Cu" signal "L12")
		(26 "In12.Cu" signal "L13GND")
		(2 "B.Cu" signal "BOTTOM")
		(9 "F.Adhes" user "F.Adhesive")
		(11 "B.Adhes" user "B.Adhesive")
		(13 "F.Paste" user "Package Geometry/Pastemask Top")
		(15 "B.Paste" user "Package Geometry/Pastemask Bottom")
		(5 "F.SilkS" user "Ref Des/Silkscreen Top")
		(7 "B.SilkS" user "Ref Des/Silkscreen Bottom")
		(1 "F.Mask" user "Board Geometry/Soldermask Top")
		(3 "B.Mask" user "Board Geometry/Soldermask Bottom")
		(17 "Dwgs.User" user "User.Drawings")
		(19 "Cmts.User" user "User.Comments")
		(21 "Eco1.User" user "User.Eco1")
		(23 "Eco2.User" user "User.Eco2")
		(25 "Edge.Cuts" user "Board Geometry/Outline")
		(27 "Margin" user)
		(31 "F.CrtYd" user "Package Geometry/Place Bound Top")
		(29 "B.CrtYd" user "Package Geometry/Place Bound Bottom")
		(35 "F.Fab" user "Ref Des/Assembly Top")
		(33 "B.Fab" user "Ref Des/Assembly Bottom")
	)
	(footprint ""
		(layer "F.Cu")
		(at 484.251 -43.9674 180)
		(property "Reference" "EU9E1"
			(at 7.2644 -5.49529 0)
			(unlocked yes)
			(layer "F.SilkS")
			(effects
				(font
					(size 0.7874 0.5842)
					(thickness 0.1524)
				)
				(justify left)
			)
		)
		(property "Value" ""
			(at 0 0 180)
			(layer "F.Fab")
			(effects
				(font
					(size 1.27 1.27)
				)
			)
		)
		(duplicate_pad_numbers_are_jumpers no)
		(pad "1" smd custom
			(at -4.3688 -3.750056 180)
			(size 0.0762 0.0762)
			(layers "F.Cu" "F.Mask" "F.Paste")
			(net "PU_SPRV_LAN_PWR_GOOD")
			(options
				(clearance outline)
				(anchor circle)
			)
			(primitives
				(gr_poly
					(pts
						(xy -0.381 -0.1524)
						(arc
							(start 0.2286 -0.1524)
							(mid 0.381 0)
							(end 0.2286 0.1524)
						)
						(xy -0.381 0.1524)
					)
					(width 0)
					(fill yes)
				)
			)
		)
		(pad "2" smd custom
			(at -4.3688 -3.24993 180)
			(size 0.0762 0.0762)
			(layers "F.Cu" "F.Mask" "F.Paste")
			(net "CLK_50M_CKMNG_SPRVLLE")
			(options
				(clearance outline)
				(anchor circle)
			)
			(primitives
				(gr_poly
					(pts
						(xy -0.381 -0.1524)
						(arc
							(start 0.2286 -0.1524)
							(mid 0.381 0)
							(end 0.2286 0.1524)
						)
						(xy -0.381 0.1524)
					)
					(width 0)
					(fill yes)
				)
			)
		)
		(pad "3" smd custom
			(at -4.3688 -2.750058 180)
			(size 0.0762 0.0762)
			(layers "F.Cu" "F.Mask" "F.Paste")
			(net "RMII_BMC_PCH_SPRNGVLLE_CRSDV_R")
			(options
				(clearance outline)
				(anchor circle)
			)
			(primitives
				(gr_poly
					(pts
						(xy -0.381 -0.1524)
						(arc
							(start 0.2286 -0.1524)
							(mid 0.381 0)
							(end 0.2286 0.1524)
						)
						(xy -0.381 0.1524)
					)
					(width 0)
					(fill yes)
				)
			)
		)
		(pad "4" smd custom
			(at -4.3688 -2.249932 180)
			(size 0.0762 0.0762)
			(layers "F.Cu" "F.Mask" "F.Paste")
			(net "PU_JTAG_SPRV_TDO")
			(options
				(clearance outline)
				(anchor circle)
			)
			(primitives
				(gr_poly
					(pts
						(xy -0.381 -0.1524)
						(arc
							(start 0.2286 -0.1524)
							(mid 0.381 0)
							(end 0.2286 0.1524)
						)
						(xy -0.381 0.1524)
					)
					(width 0)
					(fill yes)
				)
			)
		)
		(pad "5" smd custom
			(at -4.3688 -1.75006 180)
			(size 0.0762 0.0762)
			(layers "F.Cu" "F.Mask" "F.Paste")
			(net "RMII_SPRNGVLLE_BMC_PCH_RXD1_R")
			(options
				(clearance outline)
				(anchor circle)
			)
			(primitives
				(gr_poly
					(pts
						(xy -0.381 -0.1524)
						(arc
							(start 0.2286 -0.1524)
							(mid 0.381 0)
							(end 0.2286 0.1524)
						)
						(xy -0.381 0.1524)
					)
					(width 0)
					(fill yes)
				)
			)
		)
		(pad "6" smd custom
			(at -4.3688 -1.249934 180)
			(size 0.0762 0.0762)
			(layers "F.Cu" "F.Mask" "F.Paste")
			(net "RMII_SPRNGVLLE_BMC_PCH_RXD0_R")
			(options
				(clearance outline)
				(anchor circle)
			)
			(primitives
				(gr_poly
					(pts
						(xy -0.381 -0.1524)
						(arc
							(start 0.2286 -0.1524)
							(mid 0.381 0)
							(end 0.2286 0.1524)
						)
						(xy -0.381 0.1524)
					)
					(width 0)
					(fill yes)
				)
			)
		)
		(pad "7" smd custom
			(at -4.3688 -0.750062 180)
			(size 0.0762 0.0762)
			(layers "F.Cu" "F.Mask" "F.Paste")
			(net "RMII_BMC_PCH_SPRNGVLLE_TXEN")
			(options
				(clearance outline)
				(anchor circle)
			)
			(primitives
				(gr_poly
					(pts
						(xy -0.381 -0.1524)
						(arc
							(start 0.2286 -0.1524)
							(mid 0.381 0)
							(end 0.2286 0.1524)
						)
						(xy -0.381 0.1524)
					)
					(width 0)
					(fill yes)
				)
			)
		)
		(pad "8" smd custom
			(at -4.3688 -0.249936 180)
			(size 0.0762 0.0762)
			(layers "F.Cu" "F.Mask" "F.Paste")
			(net "RMII_BMC_PCH_SPRNGVLLE_TXD1")
			(options
				(clearance outline)
				(anchor circle)
			)
			(primitives
				(gr_poly
					(pts
						(xy -0.381 -0.1524)
						(arc
							(start 0.2286 -0.1524)
							(mid 0.381 0)
							(end 0.2286 0.1524)
						)
						(xy -0.381 0.1524)
					)
					(width 0)
					(fill yes)
				)
			)
		)
		(pad "9" smd custom
			(at -4.3688 0.249936 180)
			(size 0.0762 0.0762)
			(layers "F.Cu" "F.Mask" "F.Paste")
			(net "RMII_BMC_PCH_SPRNGVLLE_TXD0")
			(options
				(clearance outline)
				(anchor circle)
			)
			(primitives
				(gr_poly
					(pts
						(xy -0.381 -0.1524)
						(arc
							(start 0.2286 -0.1524)
							(mid 0.381 0)
							(end 0.2286 0.1524)
						)
						(xy -0.381 0.1524)
					)
					(width 0)
					(fill yes)
				)
			)
		)
		(pad "10" smd custom
			(at -4.3688 0.750062 180)
			(size 0.0762 0.0762)
			(layers "F.Cu" "F.Mask" "F.Paste")
			(net "P3V3_STBY")
			(options
				(clearance outline)
				(anchor circle)
			)
			(primitives
				(gr_poly
					(pts
						(xy -0.381 -0.1524)
						(arc
							(start 0.2286 -0.1524)
							(mid 0.381 0)
							(end 0.2286 0.1524)
						)
						(xy -0.381 0.1524)
					)
					(width 0)
					(fill yes)
				)
			)
		)
		(pad "11" smd custom
			(at -4.3688 1.249934 180)
			(size 0.0762 0.0762)
			(layers "F.Cu" "F.Mask" "F.Paste")
			(net "P0V9_LAN")
			(options
				(clearance outline)
				(anchor circle)
			)
			(primitives
				(gr_poly
					(pts
						(xy -0.381 -0.1524)
						(arc
							(start 0.2286 -0.1524)
							(mid 0.381 0)
							(end 0.2286 0.1524)
						)
						(xy -0.381 0.1524)
					)
					(width 0)
					(fill yes)
				)
			)
		)
		(pad "12" smd custom
			(at -4.3688 1.75006 180)
			(size 0.0762 0.0762)
			(layers "F.Cu" "F.Mask" "F.Paste")
			(net "SPI_NIC_MOSI_R")
			(options
				(clearance outline)
				(anchor circle)
			)
			(primitives
				(gr_poly
					(pts
						(xy -0.381 -0.1524)
						(arc
							(start 0.2286 -0.1524)
							(mid 0.381 0)
							(end 0.2286 0.1524)
						)
						(xy -0.381 0.1524)
					)
					(width 0)
					(fill yes)
				)
			)
		)
		(pad "13" smd custom
			(at -4.3688 2.249932 180)
			(size 0.0762 0.0762)
			(layers "F.Cu" "F.Mask" "F.Paste")
			(net "SPI_NIC_SCLK_R")
			(options
				(clearance outline)
				(anchor circle)
			)
			(primitives
				(gr_poly
					(pts
						(xy -0.381 -0.1524)
						(arc
							(start 0.2286 -0.1524)
							(mid 0.381 0)
							(end 0.2286 0.1524)
						)
						(xy -0.381 0.1524)
					)
					(width 0)
					(fill yes)
				)
			)
		)
		(pad "14" smd custom
			(at -4.3688 2.750058 180)
			(size 0.0762 0.0762)
			(layers "F.Cu" "F.Mask" "F.Paste")
			(net "SPI_NIC_MISO")
			(options
				(clearance outline)
				(anchor circle)
			)
			(primitives
				(gr_poly
					(pts
						(xy -0.381 -0.1524)
						(arc
							(start 0.2286 -0.1524)
							(mid 0.381 0)
							(end 0.2286 0.1524)
						)
						(xy -0.381 0.1524)
					)
					(width 0)
					(fill yes)
				)
			)
		)
		(pad "15" smd custom
			(at -4.3688 3.24993 180)
			(size 0.0762 0.0762)
			(layers "F.Cu" "F.Mask" "F.Paste")
			(net "SPI_NIC_CS_R_N")
			(options
				(clearance outline)
				(anchor circle)
			)
			(primitives
				(gr_poly
					(pts
						(xy -0.381 -0.1524)
						(arc
							(start 0.2286 -0.1524)
							(mid 0.381 0)
							(end 0.2286 0.1524)
						)
						(xy -0.381 0.1524)
					)
					(width 0)
					(fill yes)
				)
			)
		)
		(pad "16" smd custom
			(at -4.3688 3.750056 180)
			(size 0.0762 0.0762)
			(layers "F.Cu" "F.Mask" "F.Paste")
			(net "FM_PE_SPRV_WAKE_N")
			(options
				(clearance outline)
				(anchor circle)
			)
			(primitives
				(gr_poly
					(pts
						(xy -0.381 -0.1524)
						(arc
							(start 0.2286 -0.1524)
							(mid 0.381 0)
							(end 0.2286 0.1524)
						)
						(xy -0.381 0.1524)
					)
					(width 0)
					(fill yes)
				)
			)
		)
		(pad "17" smd custom
			(at -3.750056 4.3688 180)
			(size 0.0762 0.0762)
			(layers "F.Cu" "F.Mask" "F.Paste")
			(net "RST_PLTRST_SPRV_R_N")
			(options
				(clearance outline)
				(anchor circle)
			)
			(primitives
				(gr_poly
					(pts
						(xy -0.1524 0.381)
						(arc
							(start -0.1524 -0.2286)
							(mid 0 -0.381)
							(end 0.1524 -0.2286)
						)
						(xy 0.1524 0.381)
					)
					(width 0)
					(fill yes)
				)
			)
		)
		(pad "18" smd custom
			(at -3.250184 4.3688 180)
			(size 0.0762 0.0762)
			(layers "F.Cu" "F.Mask" "F.Paste")
			(net "PU_JTAG_SPRV_TMS")
			(options
				(clearance outline)
				(anchor circle)
			)
			(primitives
				(gr_poly
					(pts
						(xy -0.1524 0.381)
						(arc
							(start -0.1524 -0.2286)
							(mid 0 -0.381)
							(end 0.1524 -0.2286)
						)
						(xy 0.1524 0.381)
					)
					(width 0)
					(fill yes)
				)
			)
		)
		(pad "19" smd custom
			(at -2.750058 4.3688 180)
			(size 0.0762 0.0762)
			(layers "F.Cu" "F.Mask" "F.Paste")
			(net "PU_JTAG_SPRV_TCK")
			(options
				(clearance outline)
				(anchor circle)
			)
			(primitives
				(gr_poly
					(pts
						(xy -0.1524 0.381)
						(arc
							(start -0.1524 -0.2286)
							(mid 0 -0.381)
							(end 0.1524 -0.2286)
						)
						(xy 0.1524 0.381)
					)
					(width 0)
					(fill yes)
				)
			)
		)
		(pad "20" smd custom
			(at -2.250186 4.3688 180)
			(size 0.0762 0.0762)
			(layers "F.Cu" "F.Mask" "F.Paste")
			(net "PE_PCH_SPRV_RX_DN")
			(options
				(clearance outline)
				(anchor circle)
			)
			(primitives
				(gr_poly
					(pts
						(xy -0.1524 0.381)
						(arc
							(start -0.1524 -0.2286)
							(mid 0 -0.381)
							(end 0.1524 -0.2286)
						)
						(xy 0.1524 0.381)
					)
					(width 0)
					(fill yes)
				)
			)
		)
		(pad "21" smd custom
			(at -1.75006 4.3688 180)
			(size 0.0762 0.0762)
			(layers "F.Cu" "F.Mask" "F.Paste")
			(net "PE_PCH_SPRV_RX_DP")
			(options
				(clearance outline)
				(anchor circle)
			)
			(primitives
				(gr_poly
					(pts
						(xy -0.1524 0.381)
						(arc
							(start -0.1524 -0.2286)
							(mid 0 -0.381)
							(end 0.1524 -0.2286)
						)
						(xy 0.1524 0.381)
					)
					(width 0)
					(fill yes)
				)
			)
		)
		(pad "22" smd custom
			(at -1.250188 4.3688 180)
			(size 0.0762 0.0762)
			(layers "F.Cu" "F.Mask" "F.Paste")
			(net "Net_314")
			(options
				(clearance outline)
				(anchor circle)
			)
			(primitives
				(gr_poly
					(pts
						(xy -0.1524 0.381)
						(arc
							(start -0.1524 -0.2286)
							(mid 0 -0.381)
							(end 0.1524 -0.2286)
						)
						(xy 0.1524 0.381)
					)
					(width 0)
					(fill yes)
				)
			)
		)
		(pad "23" smd custom
			(at -0.750062 4.3688 180)
			(size 0.0762 0.0762)
			(layers "F.Cu" "F.Mask" "F.Paste")
			(net "PE_PCH_SPRV_TX_C_DN")
			(options
				(clearance outline)
				(anchor circle)
			)
			(primitives
				(gr_poly
					(pts
						(xy -0.1524 0.381)
						(arc
							(start -0.1524 -0.2286)
							(mid 0 -0.381)
							(end 0.1524 -0.2286)
						)
						(xy 0.1524 0.381)
					)
					(width 0)
					(fill yes)
				)
			)
		)
		(pad "24" smd custom
			(at -0.25019 4.3688 180)
			(size 0.0762 0.0762)
			(layers "F.Cu" "F.Mask" "F.Paste")
			(net "PE_PCH_SPRV_TX_C_DP")
			(options
				(clearance outline)
				(anchor circle)
			)
			(primitives
				(gr_poly
					(pts
						(xy -0.1524 0.381)
						(arc
							(start -0.1524 -0.2286)
							(mid 0 -0.381)
							(end 0.1524 -0.2286)
						)
						(xy 0.1524 0.381)
					)
					(width 0)
					(fill yes)
				)
			)
		)
		(pad "25" smd custom
			(at 0.249936 4.3688 180)
			(size 0.0762 0.0762)
			(layers "F.Cu" "F.Mask" "F.Paste")
			(net "CLK_100M_SPRV_DN")
			(options
				(clearance outline)
				(anchor circle)
			)
			(primitives
				(gr_poly
					(pts
						(xy -0.1524 0.381)
						(arc
							(start -0.1524 -0.2286)
							(mid 0 -0.381)
							(end 0.1524 -0.2286)
						)
						(xy 0.1524 0.381)
					)
					(width 0)
					(fill yes)
				)
			)
		)
		(pad "26" smd custom
			(at 0.749808 4.3688 180)
			(size 0.0762 0.0762)
			(layers "F.Cu" "F.Mask" "F.Paste")
			(net "CLK_100M_SPRV_DP")
			(options
				(clearance outline)
				(anchor circle)
			)
			(primitives
				(gr_poly
					(pts
						(xy -0.1524 0.381)
						(arc
							(start -0.1524 -0.2286)
							(mid 0 -0.381)
							(end 0.1524 -0.2286)
						)
						(xy 0.1524 0.381)
					)
					(width 0)
					(fill yes)
				)
			)
		)
		(pad "27" smd custom
			(at 1.249934 4.3688 180)
			(size 0.0762 0.0762)
			(layers "F.Cu" "F.Mask" "F.Paste")
			(net "P3V3_STBY")
			(options
				(clearance outline)
				(anchor circle)
			)
			(primitives
				(gr_poly
					(pts
						(xy -0.1524 0.381)
						(arc
							(start -0.1524 -0.2286)
							(mid 0 -0.381)
							(end 0.1524 -0.2286)
						)
						(xy 0.1524 0.381)
					)
					(width 0)
					(fill yes)
				)
			)
		)
		(pad "28" smd custom
			(at 1.749806 4.3688 180)
			(size 0.0762 0.0762)
			(layers "F.Cu" "F.Mask" "F.Paste")
			(net "PU_DEV_OFF_N")
			(options
				(clearance outline)
				(anchor circle)
			)
			(primitives
				(gr_poly
					(pts
						(xy -0.1524 0.381)
						(arc
							(start -0.1524 -0.2286)
							(mid 0 -0.381)
							(end 0.1524 -0.2286)
						)
						(xy 0.1524 0.381)
					)
					(width 0)
					(fill yes)
				)
			)
		)
		(pad "29" smd custom
			(at 2.249932 4.3688 180)
			(size 0.0762 0.0762)
			(layers "F.Cu" "F.Mask" "F.Paste")
			(net "PU_JTAG_SPRV_TDI")
			(options
				(clearance outline)
				(anchor circle)
			)
			(primitives
				(gr_poly
					(pts
						(xy -0.1524 0.381)
						(arc
							(start -0.1524 -0.2286)
							(mid 0 -0.381)
							(end 0.1524 -0.2286)
						)
						(xy 0.1524 0.381)
					)
					(width 0)
					(fill yes)
				)
			)
		)
		(pad "30" smd custom
			(at 2.750058 4.3688 180)
			(size 0.0762 0.0762)
			(layers "F.Cu" "F.Mask" "F.Paste")
			(net "LED_LAN_1_N")
			(options
				(clearance outline)
				(anchor circle)
			)
			(primitives
				(gr_poly
					(pts
						(xy -0.1524 0.381)
						(arc
							(start -0.1524 -0.2286)
							(mid 0 -0.381)
							(end 0.1524 -0.2286)
						)
						(xy 0.1524 0.381)
					)
					(width 0)
					(fill yes)
				)
			)
		)
		(pad "31" smd custom
			(at 3.24993 4.3688 180)
			(size 0.0762 0.0762)
			(layers "F.Cu" "F.Mask" "F.Paste")
			(net "LED_LAN_0_N")
			(options
				(clearance outline)
				(anchor circle)
			)
			(primitives
				(gr_poly
					(pts
						(xy -0.1524 0.381)
						(arc
							(start -0.1524 -0.2286)
							(mid 0 -0.381)
							(end 0.1524 -0.2286)
						)
						(xy 0.1524 0.381)
					)
					(width 0)
					(fill yes)
				)
			)
		)
		(pad "32" smd custom
			(at 3.750056 4.3688 180)
			(size 0.0762 0.0762)
			(layers "F.Cu" "F.Mask" "F.Paste")
			(net "P0V9_LAN")
			(options
				(clearance outline)
				(anchor circle)
			)
			(primitives
				(gr_poly
					(pts
						(xy -0.1524 0.381)
						(arc
							(start -0.1524 -0.2286)
							(mid 0 -0.381)
							(end 0.1524 -0.2286)
						)
						(xy 0.1524 0.381)
					)
					(width 0)
					(fill yes)
				)
			)
		)
		(pad "33" smd custom
			(at 4.3688 3.750056 180)
			(size 0.0762 0.0762)
			(layers "F.Cu" "F.Mask" "F.Paste")
			(net "LED_LAN_2_N")
			(options
				(clearance outline)
				(anchor circle)
			)
			(primitives
				(gr_poly
					(pts
						(xy 0.381 0.1524)
						(arc
							(start -0.2286 0.1524)
							(mid -0.381 0)
							(end -0.2286 -0.1524)
						)
						(xy 0.381 -0.1524)
					)
					(width 0)
					(fill yes)
				)
			)
		)
		(pad "34" smd custom
			(at 4.3688 3.24993 180)
			(size 0.0762 0.0762)
			(layers "F.Cu" "F.Mask" "F.Paste")
			(net "SMB_SPRINGVILLE_STBY_LVC3_SCL")
			(options
				(clearance outline)
				(anchor circle)
			)
			(primitives
				(gr_poly
					(pts
						(xy 0.381 0.1524)
						(arc
							(start -0.2286 0.1524)
							(mid -0.381 0)
							(end -0.2286 -0.1524)
						)
						(xy 0.381 -0.1524)
					)
					(width 0)
					(fill yes)
				)
			)
		)
		(pad "35" smd custom
			(at 4.3688 2.750058 180)
			(size 0.0762 0.0762)
			(layers "F.Cu" "F.Mask" "F.Paste")
			(net "IRQ_LOM_ALERT_N")
			(options
				(clearance outline)
				(anchor circle)
			)
			(primitives
				(gr_poly
					(pts
						(xy 0.381 0.1524)
						(arc
							(start -0.2286 0.1524)
							(mid -0.381 0)
							(end -0.2286 -0.1524)
						)
						(xy 0.381 -0.1524)
					)
					(width 0)
					(fill yes)
				)
			)
		)
		(pad "36" smd custom
			(at 4.3688 2.249932 180)
			(size 0.0762 0.0762)
			(layers "F.Cu" "F.Mask" "F.Paste")
			(net "SMB_SPRINGVILLE_STBY_LVC3_SDA")
			(options
				(clearance outline)
				(anchor circle)
			)
			(primitives
				(gr_poly
					(pts
						(xy 0.381 0.1524)
						(arc
							(start -0.2286 0.1524)
							(mid -0.381 0)
							(end -0.2286 -0.1524)
						)
						(xy 0.381 -0.1524)
					)
					(width 0)
					(fill yes)
				)
			)
		)
		(pad "37" smd custom
			(at 4.3688 1.75006 180)
			(size 0.0762 0.0762)
			(layers "F.Cu" "F.Mask" "F.Paste")
			(net "A_CBOT")
			(options
				(clearance outline)
				(anchor circle)
			)
			(primitives
				(gr_poly
					(pts
						(xy 0.381 0.1524)
						(arc
							(start -0.2286 0.1524)
							(mid -0.381 0)
							(end -0.2286 -0.1524)
						)
						(xy 0.381 -0.1524)
					)
					(width 0)
					(fill yes)
				)
			)
		)
		(pad "38" smd custom
			(at 4.3688 1.249934 180)
			(size 0.0762 0.0762)
			(layers "F.Cu" "F.Mask" "F.Paste")
			(net "P0V9_LAN_I210")
			(options
				(clearance outline)
				(anchor circle)
			)
			(primitives
				(gr_poly
					(pts
						(xy 0.381 0.1524)
						(arc
							(start -0.2286 0.1524)
							(mid -0.381 0)
							(end -0.2286 -0.1524)
						)
						(xy 0.381 -0.1524)
					)
					(width 0)
					(fill yes)
				)
			)
		)
		(pad "39" smd custom
			(at 4.3688 0.750062 180)
			(size 0.0762 0.0762)
			(layers "F.Cu" "F.Mask" "F.Paste")
			(net "P1V5_LAN")
			(options
				(clearance outline)
				(anchor circle)
			)
			(primitives
				(gr_poly
					(pts
						(xy 0.381 0.1524)
						(arc
							(start -0.2286 0.1524)
							(mid -0.381 0)
							(end -0.2286 -0.1524)
						)
						(xy 0.381 -0.1524)
					)
					(width 0)
					(fill yes)
				)
			)
		)
		(pad "40" smd custom
			(at 4.3688 0.249936 180)
			(size 0.0762 0.0762)
			(layers "F.Cu" "F.Mask" "F.Paste")
			(net "A_CTOP")
			(options
				(clearance outline)
				(anchor circle)
			)
			(primitives
				(gr_poly
					(pts
						(xy 0.381 0.1524)
						(arc
							(start -0.2286 0.1524)
							(mid -0.381 0)
							(end -0.2286 -0.1524)
						)
						(xy 0.381 -0.1524)
					)
					(width 0)
					(fill yes)
				)
			)
		)
		(pad "41" smd custom
			(at 4.3688 -0.249936 180)
			(size 0.0762 0.0762)
			(layers "F.Cu" "F.Mask" "F.Paste")
			(net "P3V3_STBY")
			(options
				(clearance outline)
				(anchor circle)
			)
			(primitives
				(gr_poly
					(pts
						(xy 0.381 0.1524)
						(arc
							(start -0.2286 0.1524)
							(mid -0.381 0)
							(end -0.2286 -0.1524)
						)
						(xy 0.381 -0.1524)
					)
					(width 0)
					(fill yes)
				)
			)
		)
		(pad "42" smd custom
			(at 4.3688 -0.750062 180)
			(size 0.0762 0.0762)
			(layers "F.Cu" "F.Mask" "F.Paste")
			(net "P0V9_LAN")
			(options
				(clearance outline)
				(anchor circle)
			)
			(primitives
				(gr_poly
					(pts
						(xy 0.381 0.1524)
						(arc
							(start -0.2286 0.1524)
							(mid -0.381 0)
							(end -0.2286 -0.1524)
						)
						(xy 0.381 -0.1524)
					)
					(width 0)
					(fill yes)
				)
			)
		)
	)
)
